# T6G (Grand Teton) — schematic netlist excerpt (pin names and nets, part order shuffled) for the footprints in the layout excerpt that follows; sources: Cadence DE-HDL packaged netlist, KiCad conversion of 04192023_DAF0TMB3IC0_F0TG_MB_C_brd_V02_OCP.brd

C533  Q_CAP  10UF 25V 10% X6S  pkg C0805  page 105 : A = P12V_MEM_CPU1 ; B = GND
PC463  Q_CAP  3300PF 50V 10% X7R  pkg 0402  page 193 : A = VSENSE_PVDDCR_CPU0_P0_VSEN0 ; B = VSENSE_VSS_SENSE_A_P0
C251  Q_CAP  22UF 4V 20% X6S  pkg C0402  page 69 : A = PVDDCR_CPU0_P0 ; B = GND

(kicad_pcb
	(version 20260206)
	(generator "pcbnew")
	(generator_version "10.0")
	(general
		(thickness 1.6)
		(legacy_teardrops no)
	)
	(paper "A4")
	(title_block
		(title "04192023_DAF0TMB3IC0_F0TG_MB_C_brd_V02_OCP.brd")
		(comment 1 "Grand Teton / footprints 6261-6263 of 8354")
	)
	(layers
		(0 "F.Cu" signal "TOP")
		(4 "In1.Cu" signal "GND")
		(6 "In2.Cu" signal "IN1")
		(8 "In3.Cu" signal "GND1")
		(10 "In4.Cu" signal "IN2")
		(12 "In5.Cu" signal "GND2")
		(14 "In6.Cu" signal "IN3")
		(16 "In7.Cu" signal "GND3")
		(18 "In8.Cu" signal "VCC")
		(20 "In9.Cu" signal "VCC1")
		(22 "In10.Cu" signal "GND4")
		(24 "In11.Cu" signal "IN4")
		(26 "In12.Cu" signal "GND5")
		(28 "In13.Cu" signal "IN5")
		(30 "In14.Cu" signal "GND6")
		(32 "In15.Cu" signal "IN6")
		(34 "In16.Cu" signal "GND7")
		(2 "B.Cu" signal "BOTTOM")
		(9 "F.Adhes" user "F.Adhesive")
		(11 "B.Adhes" user "B.Adhesive")
		(13 "F.Paste" user "Package Geometry/Pastemask Top")
		(15 "B.Paste" user "Package Geometry/Pastemask Bottom")
		(5 "F.SilkS" user "Ref Des/Silkscreen Top")
		(7 "B.SilkS" user "Ref Des/Silkscreen Bottom")
		(1 "F.Mask" user "Board Geometry/Soldermask Top")
		(3 "B.Mask" user "Board Geometry/Soldermask Bottom")
		(17 "Dwgs.User" user "User.Drawings")
		(19 "Cmts.User" user "User.Comments")
		(21 "Eco1.User" user "User.Eco1")
		(23 "Eco2.User" user "User.Eco2")
		(25 "Edge.Cuts" user "Board Geometry/Outline")
		(27 "Margin" user)
		(31 "F.CrtYd" user "Package Geometry/Place Bound Top")
		(29 "B.CrtYd" user "Package Geometry/Place Bound Bottom")
		(35 "F.Fab" user "Ref Des/Assembly Top")
		(33 "B.Fab" user "Ref Des/Assembly Bottom")
	)
	(footprint ""
		(layer "B.Cu")
		(at 375.331482 -147.741132 180)
		(property "Reference" "PC463"
			(at 0 0 0)
			(layer "B.SilkS")
			(hide yes)
			(effects
				(font
					(size 1.27 1.27)
				)
				(justify mirror)
			)
		)
		(property "Value" ""
			(at 0 0 0)
			(layer "B.Fab")
			(effects
				(font
					(size 1.27 1.27)
				)
				(justify mirror)
			)
		)
		(duplicate_pad_numbers_are_jumpers no)
		(fp_line
			(start 0.7874 0.4064)
			(end 0.7874 -0.4064)
			(stroke
				(width 0.1524)
				(type default)
			)
			(layer "B.SilkS")
		)
		(fp_line
			(start 0.7874 -0.4064)
			(end -0.7874 -0.4064)
			(stroke
				(width 0.1524)
				(type default)
			)
			(layer "B.SilkS")
		)
		(fp_line
			(start -0.7874 0.4064)
			(end 0.7874 0.4064)
			(stroke
				(width 0.1524)
				(type default)
			)
			(layer "B.SilkS")
		)
		(fp_line
			(start -0.7874 -0.4064)
			(end -0.7874 0.4064)
			(stroke
				(width 0.1524)
				(type default)
			)
			(layer "B.SilkS")
		)
		(fp_line
			(start 0.67945 0.3048)
			(end 0.67945 -0.305054)
			(stroke
				(width 0.1)
				(type default)
			)
			(layer "B.Fab")
		)
		(fp_line
			(start 0.67945 -0.305054)
			(end 0.12065 -0.305054)
			(stroke
				(width 0.1)
				(type default)
			)
			(layer "B.Fab")
		)
		(fp_line
			(start 0.12065 0.3048)
			(end 0.67945 0.3048)
			(stroke
				(width 0.1)
				(type default)
			)
			(layer "B.Fab")
		)
		(fp_line
			(start 0.12065 0.2794)
			(end 0.12065 0.3048)
			(stroke
				(width 0.1)
				(type default)
			)
			(layer "B.Fab")
		)
		(fp_line
			(start 0.12065 -0.2794)
			(end -0.12065 -0.2794)
			(stroke
				(width 0.1)
				(type default)
			)
			(layer "B.Fab")
		)
		(fp_line
			(start 0.12065 -0.305054)
			(end 0.12065 -0.2794)
			(stroke
				(width 0.1)
				(type default)
			)
			(layer "B.Fab")
		)
		(fp_line
			(start -0.120396 0.3048)
			(end -0.120396 0.2794)
			(stroke
				(width 0.1)
				(type default)
			)
			(layer "B.Fab")
		)
		(fp_line
			(start -0.120396 0.2794)
			(end 0.12065 0.2794)
			(stroke
				(width 0.1)
				(type default)
			)
			(layer "B.Fab")
		)
		(fp_line
			(start -0.12065 -0.2794)
			(end -0.12065 -0.3048)
			(stroke
				(width 0.1)
				(type default)
			)
			(layer "B.Fab")
		)
		(fp_line
			(start -0.12065 -0.3048)
			(end -0.67945 -0.3048)
			(stroke
				(width 0.1)
				(type default)
			)
			(layer "B.Fab")
		)
		(fp_line
			(start -0.67945 0.3048)
			(end -0.120396 0.3048)
			(stroke
				(width 0.1)
				(type default)
			)
			(layer "B.Fab")
		)
		(fp_line
			(start -0.67945 -0.3048)
			(end -0.67945 0.3048)
			(stroke
				(width 0.1)
				(type default)
			)
			(layer "B.Fab")
		)
		(pad "1" smd circle
			(at 0.40005 0)
			(size 0 0)
			(layers "B.Cu" "B.Mask" "B.Paste")
			(net "VSENSE_PVDDCR_CPU0_P0_VSEN0")
		)
		(pad "2" smd circle
			(at -0.40005 0)
			(size 0 0)
			(layers "B.Cu" "B.Mask" "B.Paste")
			(net "VSENSE_VSS_SENSE_A_P0")
		)
	)
	(footprint ""
		(layer "B.Cu")
		(at 359.740454 -246.06631 90)
		(property "Reference" "C251"
			(at 0 0 90)
			(layer "B.SilkS")
			(hide yes)
			(effects
				(font
					(size 1.27 1.27)
				)
				(justify mirror)
			)
		)
		(property "Value" ""
			(at 0 0 90)
			(layer "B.Fab")
			(effects
				(font
					(size 1.27 1.27)
				)
				(justify mirror)
			)
		)
		(duplicate_pad_numbers_are_jumpers no)
		(fp_line
			(start 0.7874 -0.4064)
			(end -0.7874 -0.4064)
			(stroke
				(width 0.1524)
				(type default)
			)
			(layer "B.SilkS")
		)
		(fp_line
			(start -0.7874 -0.4064)
			(end -0.7874 0.4064)
			(stroke
				(width 0.1524)
				(type default)
			)
			(layer "B.SilkS")
		)
		(fp_line
			(start 0.7874 0.4064)
			(end 0.7874 -0.4064)
			(stroke
				(width 0.1524)
				(type default)
			)
			(layer "B.SilkS")
		)
		(fp_line
			(start -0.7874 0.4064)
			(end 0.7874 0.4064)
			(stroke
				(width 0.1524)
				(type default)
			)
			(layer "B.SilkS")
		)
		(fp_line
			(start 0.67945 -0.305054)
			(end 0.12065 -0.305054)
			(stroke
				(width 0.1)
				(type default)
			)
			(layer "B.Fab")
		)
		(fp_line
			(start 0.12065 -0.305054)
			(end 0.12065 -0.2794)
			(stroke
				(width 0.1)
				(type default)
			)
			(layer "B.Fab")
		)
		(fp_line
			(start -0.12065 -0.3048)
			(end -0.67945 -0.3048)
			(stroke
				(width 0.1)
				(type default)
			)
			(layer "B.Fab")
		)
		(fp_line
			(start -0.67945 -0.3048)
			(end -0.67945 0.3048)
			(stroke
				(width 0.1)
				(type default)
			)
			(layer "B.Fab")
		)
		(fp_line
			(start 0.12065 -0.2794)
			(end -0.12065 -0.2794)
			(stroke
				(width 0.1)
				(type default)
			)
			(layer "B.Fab")
		)
		(fp_line
			(start -0.12065 -0.2794)
			(end -0.12065 -0.3048)
			(stroke
				(width 0.1)
				(type default)
			)
			(layer "B.Fab")
		)
		(fp_line
			(start 0.12065 0.2794)
			(end 0.12065 0.3048)
			(stroke
				(width 0.1)
				(type default)
			)
			(layer "B.Fab")
		)
		(fp_line
			(start -0.120396 0.2794)
			(end 0.12065 0.2794)
			(stroke
				(width 0.1)
				(type default)
			)
			(layer "B.Fab")
		)
		(fp_line
			(start 0.67945 0.3048)
			(end 0.67945 -0.305054)
			(stroke
				(width 0.1)
				(type default)
			)
			(layer "B.Fab")
		)
		(fp_line
			(start 0.12065 0.3048)
			(end 0.67945 0.3048)
			(stroke
				(width 0.1)
				(type default)
			)
			(layer "B.Fab")
		)
		(fp_line
			(start -0.120396 0.3048)
			(end -0.120396 0.2794)
			(stroke
				(width 0.1)
				(type default)
			)
			(layer "B.Fab")
		)
		(fp_line
			(start -0.67945 0.3048)
			(end -0.120396 0.3048)
			(stroke
				(width 0.1)
				(type default)
			)
			(layer "B.Fab")
		)
		(pad "1" smd circle
			(at 0.40005 0 270)
			(size 0 0)
			(layers "B.Cu" "B.Mask" "B.Paste")
			(net "PVDDCR_CPU0_P0")
		)
		(pad "2" smd circle
			(at -0.40005 0 270)
			(size 0 0)
			(layers "B.Cu" "B.Mask" "B.Paste")
			(net "GND")
		)
	)
	(footprint ""
		(layer "B.Cu")
		(at 176.072292 -192.66027)
		(property "Reference" "C533"
			(at 0 0 0)
			(layer "B.SilkS")
			(hide yes)
			(effects
				(font
					(size 1.27 1.27)
				)
				(justify mirror)
			)
		)
		(property "Value" ""
			(at 0 0 0)
			(layer "B.Fab")
			(effects
				(font
					(size 1.27 1.27)
				)
				(justify mirror)
			)
		)
		(duplicate_pad_numbers_are_jumpers no)
		(fp_line
			(start -1.524 -0.762)
			(end -1.524 0.762)
			(stroke
				(width 0.1524)
				(type default)
			)
			(layer "B.SilkS")
		)
		(fp_line
			(start -1.524 0.762)
			(end 1.524 0.762)
			(stroke
				(width 0.1524)
				(type default)
			)
			(layer "B.SilkS")
		)
		(fp_line
			(start 1.524 -0.762)
			(end -1.524 -0.762)
			(stroke
				(width 0.1524)
				(type default)
			)
			(layer "B.SilkS")
		)
		(fp_line
			(start 1.524 0.762)
			(end 1.524 -0.762)
			(stroke
				(width 0.1524)
				(type default)
			)
			(layer "B.SilkS")
		)
		(fp_line
			(start -1.1049 -0.724916)
			(end 1.1049 -0.724916)
			(stroke
				(width 0.1)
				(type default)
			)
			(layer "B.Fab")
		)
		(fp_line
			(start -1.1049 0.724916)
			(end -1.1049 -0.724916)
			(stroke
				(width 0.1)
				(type default)
			)
			(layer "B.Fab")
		)
		(fp_line
			(start 1.1049 -0.724916)
			(end 1.1049 0.724916)
			(stroke
				(width 0.1)
				(type default)
			)
			(layer "B.Fab")
		)
		(fp_line
			(start 1.1049 0.724916)
			(end -1.1049 0.724916)
			(stroke
				(width 0.1)
				(type default)
			)
			(layer "B.Fab")
		)
		(pad "1" smd rect
			(at 0.889 0)
			(size 1.016 1.27)
			(layers "B.Cu" "B.Mask" "B.Paste")
			(net "P12V_MEM_CPU1")
		)
		(pad "2" smd rect
			(at -0.889 0)
			(size 1.016 1.27)
			(layers "B.Cu" "B.Mask" "B.Paste")
			(net "GND")
		)
	)
)
